# BASEBOARD_FAB2 (Tioga Pass) — schematic netlist excerpt (pin names and nets, part order shuffled) for the footprints in the layout excerpt that follows; sources: Cadence DE-HDL packaged netlist, KiCad conversion of Wiwynn_Tioga_Pass_MB.brd

C4M6  CAPP  68UF 16V 20% TANT  pkg 3018  page 195 : A = P12V_STBY ; B = GND
C4T4  CAP  100UF 4V 20% X5R  pkg 0805  page 217 : A = PVDDQ_ABC ; B = GND
R1L23  RES  1.00K 1% CHIP  pkg 0402  page 111 : A = XDP_PWRGD_RST_N ; B = P3V3_STBY

(kicad_pcb
	(version 20260206)
	(generator "pcbnew")
	(generator_version "10.0")
	(general
		(thickness 1.6)
		(legacy_teardrops no)
	)
	(paper "A4")
	(title_block
		(title "Wiwynn_Tioga_Pass_MB.brd")
		(comment 1 "Tioga Pass / footprints 4167-4169 of 4770")
	)
	(layers
		(0 "F.Cu" signal "TOP")
		(4 "In1.Cu" signal "L2GND")
		(6 "In2.Cu" signal "L3")
		(8 "In3.Cu" signal "L4GND")
		(10 "In4.Cu" signal "L5")
		(12 "In5.Cu" signal "L6GND")
		(14 "In6.Cu" signal "L7VCC")
		(16 "In7.Cu" signal "L8VCC")
		(18 "In8.Cu" signal "L9GND")
		(20 "In9.Cu" signal "L10")
		(22 "In10.Cu" signal "L11GND")
		(24 "In11.Cu" signal "L12")
		(26 "In12.Cu" signal "L13GND")
		(2 "B.Cu" signal "BOTTOM")
		(9 "F.Adhes" user "F.Adhesive")
		(11 "B.Adhes" user "B.Adhesive")
		(13 "F.Paste" user "Package Geometry/Pastemask Top")
		(15 "B.Paste" user "Package Geometry/Pastemask Bottom")
		(5 "F.SilkS" user "Ref Des/Silkscreen Top")
		(7 "B.SilkS" user "Ref Des/Silkscreen Bottom")
		(1 "F.Mask" user "Board Geometry/Soldermask Top")
		(3 "B.Mask" user "Board Geometry/Soldermask Bottom")
		(17 "Dwgs.User" user "User.Drawings")
		(19 "Cmts.User" user "User.Comments")
		(21 "Eco1.User" user "User.Eco1")
		(23 "Eco2.User" user "User.Eco2")
		(25 "Edge.Cuts" user "Board Geometry/Outline")
		(27 "Margin" user)
		(31 "F.CrtYd" user "Package Geometry/Place Bound Top")
		(29 "B.CrtYd" user "Package Geometry/Place Bound Bottom")
		(35 "F.Fab" user "Ref Des/Assembly Top")
		(33 "B.Fab" user "Ref Des/Assembly Bottom")
	)
	(footprint ""
		(layer "B.Cu")
		(at 276.606 -26.868374 90)
		(property "Reference" "C4T4"
			(at 0 0 90)
			(layer "B.SilkS")
			(hide yes)
			(effects
				(font
					(size 1.27 1.27)
				)
				(justify mirror)
			)
		)
		(property "Value" ""
			(at 0 0 90)
			(layer "B.Fab")
			(effects
				(font
					(size 1.27 1.27)
				)
				(justify mirror)
			)
		)
		(duplicate_pad_numbers_are_jumpers no)
		(fp_rect
			(start 0.7239 1.9939)
			(end -0.7239 -0.2159)
			(stroke
				(width 0)
				(type default)
			)
			(fill no)
			(layer "B.CrtYd")
		)
		(fp_line
			(start 0.7239 -0.2159)
			(end 0.7239 1.9939)
			(stroke
				(width 0.1)
				(type default)
			)
			(layer "B.Fab")
		)
		(fp_line
			(start -0.7239 -0.2159)
			(end 0.7239 -0.2159)
			(stroke
				(width 0.1)
				(type default)
			)
			(layer "B.Fab")
		)
		(fp_line
			(start 0.7239 1.9939)
			(end -0.7239 1.9939)
			(stroke
				(width 0.1)
				(type default)
			)
			(layer "B.Fab")
		)
		(fp_line
			(start -0.7239 1.9939)
			(end -0.7239 -0.2159)
			(stroke
				(width 0.1)
				(type default)
			)
			(layer "B.Fab")
		)
		(pad "1" smd rect
			(at 0 0 270)
			(size 1.27 1.016)
			(layers "B.Cu" "B.Mask" "B.Paste")
			(net "PVDDQ_ABC")
		)
		(pad "2" smd rect
			(at 0 1.778 270)
			(size 1.27 1.016)
			(layers "B.Cu" "B.Mask" "B.Paste")
			(net "GND")
		)
		(zone
			(layer "B.Cu")
			(hatch none 0.5)
			(connect_pads
				(clearance 0)
			)
			(min_thickness 0.25)
			(keepout
				(tracks not_allowed)
				(vias allowed)
				(pads allowed)
				(copperpour not_allowed)
				(footprints allowed)
			)
			(placement
				(enabled no)
				(sheetname "")
			)
			(fill
				(thermal_gap 0.5)
				(thermal_bridge_width 0.5)
				(island_removal_mode 0)
			)
			(polygon
				(pts
					(xy 277.876 -27.503374) (xy 277.114 -27.503374) (xy 277.114 -26.233374) (xy 277.876 -26.233374)
				)
			)
		)
	)
	(footprint ""
		(layer "B.Cu")
		(at 462.801208 -145.415254)
		(property "Reference" "R1L23"
			(at 0 0 0)
			(layer "B.SilkS")
			(hide yes)
			(effects
				(font
					(size 1.27 1.27)
				)
				(justify mirror)
			)
		)
		(property "Value" ""
			(at 0 0 0)
			(layer "B.Fab")
			(effects
				(font
					(size 1.27 1.27)
				)
				(justify mirror)
			)
		)
		(duplicate_pad_numbers_are_jumpers no)
		(fp_poly
			(pts
				(xy 0.2794 -0.1016) (xy -0.2794 -0.1016) (xy -0.2794 0.9906) (xy 0.2794 0.9906)
			)
			(stroke
				(width 0)
				(type default)
			)
			(fill no)
			(layer "B.CrtYd")
		)
		(fp_line
			(start -0.2794 -0.1016)
			(end 0.2794 -0.1016)
			(stroke
				(width 0.1)
				(type default)
			)
			(layer "B.Fab")
		)
		(fp_line
			(start -0.2794 0.9906)
			(end -0.2794 -0.1016)
			(stroke
				(width 0.1)
				(type default)
			)
			(layer "B.Fab")
		)
		(fp_line
			(start 0.2794 -0.1016)
			(end 0.2794 0.9906)
			(stroke
				(width 0.1)
				(type default)
			)
			(layer "B.Fab")
		)
		(fp_line
			(start 0.2794 0.9906)
			(end -0.2794 0.9906)
			(stroke
				(width 0.1)
				(type default)
			)
			(layer "B.Fab")
		)
		(pad "1" smd rect
			(at 0 0 180)
			(size 0.508 0.508)
			(layers "B.Cu" "B.Mask" "B.Paste")
			(net "XDP_PWRGD_RST_N")
		)
		(pad "2" smd rect
			(at 0 0.889 180)
			(size 0.508 0.508)
			(layers "B.Cu" "B.Mask" "B.Paste")
			(net "P3V3_STBY")
		)
		(zone
			(layer "B.Cu")
			(hatch none 0.5)
			(connect_pads
				(clearance 0)
			)
			(min_thickness 0.25)
			(keepout
				(tracks allowed)
				(vias not_allowed)
				(pads allowed)
				(copperpour not_allowed)
				(footprints allowed)
			)
			(placement
				(enabled no)
				(sheetname "")
			)
			(fill
				(thermal_gap 0.5)
				(thermal_bridge_width 0.5)
				(island_removal_mode 0)
			)
			(polygon
				(pts
					(xy 463.055208 -145.161254) (xy 462.547208 -145.161254) (xy 462.547208 -144.780254) (xy 463.055208 -144.780254)
				)
			)
		)
		(zone
			(layer "B.Cu")
			(hatch none 0.5)
			(connect_pads
				(clearance 0)
			)
			(min_thickness 0.25)
			(keepout
				(tracks not_allowed)
				(vias allowed)
				(pads allowed)
				(copperpour not_allowed)
				(footprints allowed)
			)
			(placement
				(enabled no)
				(sheetname "")
			)
			(fill
				(thermal_gap 0.5)
				(thermal_bridge_width 0.5)
				(island_removal_mode 0)
			)
			(polygon
				(pts
					(xy 463.055208 -144.780254) (xy 462.547208 -144.780254) (xy 462.547208 -145.161254) (xy 463.055208 -145.161254)
				)
			)
		)
	)
	(footprint ""
		(layer "B.Cu")
		(at 333.291688 -124.887482 90)
		(property "Reference" "C4M6"
			(at -0.15367 10.5918 0)
			(unlocked yes)
			(layer "B.SilkS")
			(effects
				(font
					(size 0.7874 0.5842)
					(thickness 0.1524)
				)
				(justify mirror)
			)
		)
		(property "Value" ""
			(at 0 0 90)
			(layer "B.Fab")
			(effects
				(font
					(size 1.27 1.27)
				)
				(justify mirror)
			)
		)
		(duplicate_pad_numbers_are_jumpers no)
		(fp_line
			(start 2.563114 -1.616456)
			(end 2.563114 1.633728)
			(stroke
				(width 0.1524)
				(type default)
			)
			(layer "B.SilkS")
		)
		(fp_line
			(start 1.6002 -1.616456)
			(end 2.563114 -1.616456)
			(stroke
				(width 0.1524)
				(type default)
			)
			(layer "B.SilkS")
		)
		(fp_line
			(start -1.6002 -1.616456)
			(end -2.504948 -1.616456)
			(stroke
				(width 0.1524)
				(type default)
			)
			(layer "B.SilkS")
		)
		(fp_line
			(start -2.504948 -1.616456)
			(end -2.504948 1.633728)
			(stroke
				(width 0.1524)
				(type default)
			)
			(layer "B.SilkS")
		)
		(fp_line
			(start 2.563114 1.633728)
			(end 1.6002 1.633728)
			(stroke
				(width 0.1524)
				(type default)
			)
			(layer "B.SilkS")
		)
		(fp_line
			(start -2.504948 1.633728)
			(end -1.6002 1.633728)
			(stroke
				(width 0.1524)
				(type default)
			)
			(layer "B.SilkS")
		)
		(fp_line
			(start 2.286 7.366)
			(end 2.286 1.632712)
			(stroke
				(width 0.1524)
				(type default)
			)
			(layer "B.SilkS")
		)
		(fp_line
			(start 2.286 7.366)
			(end 1.60147 7.366)
			(stroke
				(width 0.1524)
				(type default)
			)
			(layer "B.SilkS")
		)
		(fp_line
			(start -2.286 7.366)
			(end -2.286 1.63195)
			(stroke
				(width 0.1524)
				(type default)
			)
			(layer "B.SilkS")
		)
		(fp_line
			(start -2.286 7.366)
			(end -1.600708 7.366)
			(stroke
				(width 0.1524)
				(type default)
			)
			(layer "B.SilkS")
		)
		(fp_rect
			(start 2.286 7.366)
			(end -2.286 -0.254)
			(stroke
				(width 0)
				(type default)
			)
			(fill no)
			(layer "B.CrtYd")
		)
		(fp_line
			(start 2.286 -0.254)
			(end -2.286 -0.254)
			(stroke
				(width 0.1)
				(type default)
			)
			(layer "B.Fab")
		)
		(fp_line
			(start -2.286 -0.254)
			(end -2.286 7.366)
			(stroke
				(width 0.1)
				(type default)
			)
			(layer "B.Fab")
		)
		(fp_line
			(start 2.286 7.366)
			(end 2.286 -0.254)
			(stroke
				(width 0.1)
				(type default)
			)
			(layer "B.Fab")
		)
		(fp_line
			(start -2.286 7.366)
			(end 2.286 7.366)
			(stroke
				(width 0.1)
				(type default)
			)
			(layer "B.Fab")
		)
		(pad "1" smd rect
			(at 0 0 270)
			(size 2.54 3.048)
			(layers "B.Cu" "B.Mask" "B.Paste")
			(net "P12V_STBY")
		)
		(pad "2" smd rect
			(at 0 7.112 270)
			(size 2.54 3.048)
			(layers "B.Cu" "B.Mask" "B.Paste")
			(net "GND")
		)
	)
)
